(kicad_pcb
	(version 20241229)
	(generator "pcbnew")
	(generator_version "9.0")
	(general
		(thickness 1.6)
		(legacy_teardrops no)
	)
	(paper "A4")
	(title_block
		(title "GMSL Deserializer")
		(date "2025-10-09")
		(rev "1.0.4")
		(company "Antmicro Ltd")
		(comment 1 "www.antmicro.com")
		(comment 9 "footprints 119-123 of 235")
	)
	(layers
		(0 "F.Cu" signal)
		(4 "In1.Cu" power)
		(6 "In2.Cu" power)
		(2 "B.Cu" signal)
		(9 "F.Adhes" user "F.Adhesive")
		(11 "B.Adhes" user "B.Adhesive")
		(13 "F.Paste" user)
		(15 "B.Paste" user)
		(5 "F.SilkS" user "F.Silkscreen")
		(7 "B.SilkS" user "B.Silkscreen")
		(1 "F.Mask" user)
		(3 "B.Mask" user)
		(17 "Dwgs.User" user "User.Drawings")
		(19 "Cmts.User" user "User.Comments")
		(21 "Eco1.User" user "User.Eco1")
		(23 "Eco2.User" user "User.Eco2")
		(25 "Edge.Cuts" user)
		(27 "Margin" user)
		(31 "F.CrtYd" user "F.Courtyard")
		(29 "B.CrtYd" user "B.Courtyard")
		(35 "F.Fab" user)
		(33 "B.Fab" user)
	)
	(footprint "antmicro-footprints:C_0603_1608Metric"
		(layer "F.Cu")
		(at 173.99 53.34 180)
		(descr "Capacitor SMD 0603")
		(tags "capacitor 0603")
		(property "Reference" "C1"
			(at -1.156321 0.115777 0)
			(layer "F.SilkS")
			(effects
				(font
					(size 0.7 0.7)
					(thickness 0.15)
				)
				(justify left bottom)
			)
		)
		(property "Value" "C_10u_25V_0603"
			(at -1.42757 1.770288 0)
			(layer "F.Fab")
			(effects
				(font
					(size 0.7 0.7)
					(thickness 0.15)
				)
				(justify right bottom)
			)
		)
		(property "Datasheet" "https://product.tdk.com/en/search/capacitor/ceramic/mlcc/info?part_no=C1608X5R1E106M080AC"
			(at 0 0 180)
			(layer "F.Fab")
			(hide yes)
			(effects
				(font
					(size 1.27 1.27)
					(thickness 0.15)
				)
			)
		)
		(property "Description" "SMD Multilayer Ceramic Capacitor, 10 µF, 25 V, 0603 [1608 Metric], ± 20%, X5R, C"
			(at 0 0 180)
			(layer "F.Fab")
			(hide yes)
			(effects
				(font
					(size 1.27 1.27)
					(thickness 0.15)
				)
			)
		)
		(property "Author" "Antmicro"
			(at 347.98 106.68 0)
			(layer "F.Fab")
			(hide yes)
			(effects
				(font
					(size 1 1)
					(thickness 0.15)
				)
			)
		)
		(property "Dielectric" ""
			(at 347.98 106.68 0)
			(layer "F.Fab")
			(hide yes)
			(effects
				(font
					(size 1 1)
					(thickness 0.15)
				)
			)
		)
		(property "License" "Apache-2.0"
			(at 347.98 106.68 0)
			(layer "F.Fab")
			(hide yes)
			(effects
				(font
					(size 1 1)
					(thickness 0.15)
				)
			)
		)
		(property "MPN" "C1608X5R1E106M080AC"
			(at 347.98 106.68 0)
			(layer "F.Fab")
			(hide yes)
			(effects
				(font
					(size 1 1)
					(thickness 0.15)
				)
			)
		)
		(property "Manufacturer" "TDK"
			(at 347.98 106.68 0)
			(layer "F.Fab")
			(hide yes)
			(effects
				(font
					(size 1 1)
					(thickness 0.15)
				)
			)
		)
		(property "Val" "10u"
			(at 347.98 106.68 0)
			(layer "F.Fab")
			(hide yes)
			(effects
				(font
					(size 1 1)
					(thickness 0.15)
				)
			)
		)
		(property "Voltage" "25V"
			(at 347.98 106.68 0)
			(layer "F.Fab")
			(hide yes)
			(effects
				(font
					(size 1 1)
					(thickness 0.15)
				)
			)
		)
		(sheetname "/Connectors/")
		(sheetfile "connectors.kicad_sch")
		(attr smd)
		(fp_line
			(start -0.15 0.4)
			(end 0.15 0.4)
			(stroke
				(width 0.15)
				(type solid)
			)
			(layer "F.SilkS")
		)
		(fp_line
			(start -0.15 -0.4)
			(end 0.15 -0.4)
			(stroke
				(width 0.15)
				(type solid)
			)
			(layer "F.SilkS")
		)
		(fp_rect
			(start -1.25 -0.65)
			(end 1.25 0.65)
			(stroke
				(width 0.05)
				(type solid)
			)
			(fill no)
			(layer "F.CrtYd")
		)
		(fp_rect
			(start -0.8 -0.4)
			(end 0.8 0.4)
			(stroke
				(width 0.15)
				(type solid)
			)
			(fill no)
			(layer "F.Fab")
		)
		(pad "1" smd roundrect
			(at -0.7 0 180)
			(size 0.8 1)
			(layers "F.Cu" "F.Mask" "F.Paste")
			(roundrect_rratio 0.2)
			(net 1 "GND")
			(pintype "passive")
		)
		(pad "2" smd roundrect
			(at 0.7 0 180)
			(size 0.8 1)
			(layers "F.Cu" "F.Mask" "F.Paste")
			(roundrect_rratio 0.2)
			(net 2 "/Connectors/DC_UNFUSED")
			(pintype "passive")
		)
	)
	(footprint "antmicro-footprints:C_0402_1005Metric"
		(layer "F.Cu")
		(at 123.571 66.548 90)
		(descr "Capacitor SMD 0402")
		(tags "capacitor SMD 0402")
		(property "Reference" "C10"
			(at -1.905 1.27 90)
			(layer "F.SilkS")
			(effects
				(font
					(size 0.7 0.7)
					(thickness 0.15)
				)
				(justify left bottom)
			)
		)
		(property "Value" "C_10n_0402"
			(at -1.022927 2.155213 90)
			(layer "F.Fab")
			(effects
				(font
					(size 0.7 0.7)
					(thickness 0.15)
				)
				(justify left bottom)
			)
		)
		(property "Datasheet" "https://www.murata.com/products/productdetail?partno=GRM155R71H103KA88%23"
			(at 0 0 90)
			(layer "F.Fab")
			(hide yes)
			(effects
				(font
					(size 1.27 1.27)
					(thickness 0.15)
				)
			)
		)
		(property "Description" "SMD Multilayer Ceramic Capacitor, 10000 pF, 50 V, 0402 [1005 Metric], ± 10%, X7R, GRM Series"
			(at 0 0 90)
			(layer "F.Fab")
			(hide yes)
			(effects
				(font
					(size 1.27 1.27)
					(thickness 0.15)
				)
			)
		)
		(property "Author" "Antmicro"
			(at 190.119 -57.023 0)
			(layer "F.Fab")
			(hide yes)
			(effects
				(font
					(size 1 1)
					(thickness 0.15)
				)
			)
		)
		(property "Dielectric" "X7R"
			(at 190.119 -57.023 0)
			(layer "F.Fab")
			(hide yes)
			(effects
				(font
					(size 1 1)
					(thickness 0.15)
				)
			)
		)
		(property "License" "Apache-2.0"
			(at 190.119 -57.023 0)
			(layer "F.Fab")
			(hide yes)
			(effects
				(font
					(size 1 1)
					(thickness 0.15)
				)
			)
		)
		(property "MPN" "GRM155R71H103KA88D"
			(at 190.119 -57.023 0)
			(layer "F.Fab")
			(hide yes)
			(effects
				(font
					(size 1 1)
					(thickness 0.15)
				)
			)
		)
		(property "Manufacturer" "Murata"
			(at 190.119 -57.023 0)
			(layer "F.Fab")
			(hide yes)
			(effects
				(font
					(size 1 1)
					(thickness 0.15)
				)
			)
		)
		(property "Val" "10n"
			(at 190.119 -57.023 0)
			(layer "F.Fab")
			(hide yes)
			(effects
				(font
					(size 1 1)
					(thickness 0.15)
				)
			)
		)
		(property "Voltage" "50V"
			(at 190.119 -57.023 0)
			(layer "F.Fab")
			(hide yes)
			(effects
				(font
					(size 1 1)
					(thickness 0.15)
				)
			)
		)
		(sheetname "/Power/")
		(sheetfile "power.kicad_sch")
		(attr smd)
		(fp_rect
			(start -0.925 -0.47)
			(end 0.925 0.47)
			(stroke
				(width 0.05)
				(type default)
			)
			(fill no)
			(layer "F.CrtYd")
		)
		(fp_line
			(start 0.504 -0.25)
			(end 0.504 0.248)
			(stroke
				(width 0.15)
				(type solid)
			)
			(layer "F.Fab")
		)
		(fp_line
			(start -0.494 -0.25)
			(end 0.504 -0.25)
			(stroke
				(width 0.15)
				(type solid)
			)
			(layer "F.Fab")
		)
		(fp_line
			(start 0.504 0.248)
			(end -0.494 0.248)
			(stroke
				(width 0.15)
				(type solid)
			)
			(layer "F.Fab")
		)
		(fp_line
			(start -0.494 0.248)
			(end -0.494 -0.25)
			(stroke
				(width 0.15)
				(type solid)
			)
			(layer "F.Fab")
		)
		(pad "1" smd roundrect
			(at -0.48 0 90)
			(size 0.59 0.64)
			(layers "F.Cu" "F.Mask" "F.Paste")
			(roundrect_rratio 0.25)
			(net 1 "GND")
			(pintype "passive")
		)
		(pad "2" smd roundrect
			(at 0.48 0 90)
			(size 0.59 0.64)
			(layers "F.Cu" "F.Mask" "F.Paste")
			(roundrect_rratio 0.25)
			(net 4 "+12V")
			(pintype "passive")
		)
	)
	(footprint "antmicro-footprints:R_0402_1005Metric"
		(layer "F.Cu")
		(at 170.687 67.818)
		(descr "Resistor SMD 0402")
		(tags "resistor SMD 0402")
		(property "Reference" "R69"
			(at -3.147968 0.344135 0)
			(layer "F.SilkS")
			(effects
				(font
					(size 0.7 0.7)
					(thickness 0.15)
				)
				(justify left bottom)
			)
		)
		(property "Value" "R_100R_0402"
			(at -1.011843 1.772047 0)
			(layer "F.Fab")
			(effects
				(font
					(size 0.7 0.7)
					(thickness 0.15)
				)
				(justify left bottom)
			)
		)
		(property "Datasheet" "https://www.bourns.com/docs/product-datasheets/cr.pdf"
			(at 0 0 0)
			(layer "F.Fab")
			(hide yes)
			(effects
				(font
					(size 1.27 1.27)
					(thickness 0.15)
				)
			)
		)
		(property "Description" "SMD Chip Resistor, 100 ohm, ± 1%, 62.5 mW, 0402 [1005 Metric], Thick Film, General Purpose"
			(at 0 0 0)
			(layer "F.Fab")
			(hide yes)
			(effects
				(font
					(size 1.27 1.27)
					(thickness 0.15)
				)
			)
		)
		(property "Author" "Antmicro"
			(at 0 0 0)
			(layer "F.Fab")
			(hide yes)
			(effects
				(font
					(size 1 1)
					(thickness 0.15)
				)
			)
		)
		(property "License" "Apache-2.0"
			(at 0 0 0)
			(layer "F.Fab")
			(hide yes)
			(effects
				(font
					(size 1 1)
					(thickness 0.15)
				)
			)
		)
		(property "MPN" "CR0402-FX-1000GLF"
			(at 0 0 0)
			(layer "F.Fab")
			(hide yes)
			(effects
				(font
					(size 1 1)
					(thickness 0.15)
				)
			)
		)
		(property "Manufacturer" "Bourns"
			(at 0 0 0)
			(layer "F.Fab")
			(hide yes)
			(effects
				(font
					(size 1 1)
					(thickness 0.15)
				)
			)
		)
		(property "Tolerance" "1%"
			(at 0 0 0)
			(layer "F.Fab")
			(hide yes)
			(effects
				(font
					(size 1 1)
					(thickness 0.15)
				)
			)
		)
		(property "Val" "100R"
			(at 0 0 0)
			(layer "F.Fab")
			(hide yes)
			(effects
				(font
					(size 1 1)
					(thickness 0.15)
				)
			)
		)
		(sheetname "/Connectors/")
		(sheetfile "connectors.kicad_sch")
		(attr smd exclude_from_pos_files exclude_from_bom dnp)
		(fp_rect
			(start -0.925 -0.47)
			(end 0.925 0.47)
			(stroke
				(width 0.05)
				(type default)
			)
			(fill no)
			(layer "F.CrtYd")
		)
		(fp_rect
			(start -0.5 -0.25)
			(end 0.5 0.25)
			(stroke
				(width 0.15)
				(type solid)
			)
			(fill no)
			(layer "F.Fab")
		)
		(pad "1" smd roundrect
			(at -0.48 0)
			(size 0.59 0.64)
			(layers "F.Cu" "F.Mask" "F.Paste")
			(roundrect_rratio 0.25)
			(net 87 "/Connectors/MFP8")
			(pintype "passive")
		)
		(pad "2" smd roundrect
			(at 0.48 0)
			(size 0.59 0.64)
			(layers "F.Cu" "F.Mask" "F.Paste")
			(roundrect_rratio 0.25)
			(net 134 "Net-(U8-A_{2})")
			(pintype "passive")
		)
	)
	(footprint "antmicro-footprints:TSOT23-6"
		(layer "F.Cu")
		(at 123.626 84.178 180)
		(property "Reference" "U5"
			(at -0.508 2.032 0)
			(layer "F.SilkS")
			(effects
				(font
					(size 0.7 0.7)
					(thickness 0.15)
				)
				(justify right bottom)
			)
		)
		(property "Value" "AP62301_TSOT"
			(at 0 2.6 0)
			(layer "F.Fab")
			(effects
				(font
					(size 0.7 0.7)
					(thickness 0.15)
				)
				(justify right bottom)
			)
		)
		(property "Datasheet" "https://www.diodes.com/assets/Datasheets/AP62300_AP62301_AP62300T.pdf"
			(at 0 0 180)
			(layer "F.Fab")
			(hide yes)
			(effects
				(font
					(size 1.27 1.27)
					(thickness 0.15)
				)
			)
		)
		(property "Description" "DC-DC Switching Synchronous Buck Regulator, Adjustable, 4.2V-18Vin, 0.8V-7V/3A out, TSOT-26-6"
			(at 0 0 180)
			(layer "F.Fab")
			(hide yes)
			(effects
				(font
					(size 1.27 1.27)
					(thickness 0.15)
				)
			)
		)
		(property "Author" "Antmicro"
			(at 247.252 168.356 0)
			(layer "F.Fab")
			(hide yes)
			(effects
				(font
					(size 1 1)
					(thickness 0.15)
				)
			)
		)
		(property "License" "Apache-2.0"
			(at 247.252 168.356 0)
			(layer "F.Fab")
			(hide yes)
			(effects
				(font
					(size 1 1)
					(thickness 0.15)
				)
			)
		)
		(property "MPN" "AP62301WU-7"
			(at 247.252 168.356 0)
			(layer "F.Fab")
			(hide yes)
			(effects
				(font
					(size 1 1)
					(thickness 0.15)
				)
			)
		)
		(property "Manufacturer" "Diodes Incorporated"
			(at 247.252 168.356 0)
			(layer "F.Fab")
			(hide yes)
			(effects
				(font
					(size 1 1)
					(thickness 0.15)
				)
			)
		)
		(sheetname "/Power/")
		(sheetfile "power.kicad_sch")
		(attr smd)
		(fp_line
			(start 1 1.55)
			(end 1 1.4)
			(stroke
				(width 0.15)
				(type solid)
			)
			(layer "F.SilkS")
		)
		(fp_line
			(start 1 1.55)
			(end -1 1.55)
			(stroke
				(width 0.15)
				(type solid)
			)
			(layer "F.SilkS")
		)
		(fp_line
			(start 1 -1.497)
			(end 1 -1.375)
			(stroke
				(width 0.15)
				(type solid)
			)
			(layer "F.SilkS")
		)
		(fp_line
			(start 1 -1.497)
			(end -1 -1.5)
			(stroke
				(width 0.15)
				(type solid)
			)
			(layer "F.SilkS")
		)
		(fp_line
			(start -1 1.55)
			(end -1 1.4)
			(stroke
				(width 0.15)
				(type solid)
			)
			(layer "F.SilkS")
		)
		(fp_line
			(start -1 -1.5)
			(end -1 -1.375)
			(stroke
				(width 0.15)
				(type solid)
			)
			(layer "F.SilkS")
		)
		(fp_circle
			(center -1.44 -1.5)
			(end -1.39 -1.5)
			(stroke
				(width 0.15)
				(type solid)
			)
			(fill yes)
			(layer "F.SilkS")
		)
		(fp_rect
			(start 1.93 -1.7)
			(end -1.93 1.7)
			(stroke
				(width 0.05)
				(type solid)
			)
			(fill no)
			(layer "F.CrtYd")
		)
		(fp_line
			(start -0.45 -1.521)
			(end -0.876 -1.096)
			(stroke
				(width 0.15)
				(type solid)
			)
			(layer "F.Fab")
		)
		(fp_rect
			(start 0.875 1.528)
			(end -0.875 -1.525)
			(stroke
				(width 0.15)
				(type solid)
			)
			(fill no)
			(layer "F.Fab")
		)
		(pad "1" smd rect
			(at -1.301 -0.947 90)
			(size 0.7 1.2)
			(layers "F.Cu" "F.Mask" "F.Paste")
			(net 1 "GND")
			(pinfunction "GND")
			(pintype "power_in")
		)
		(pad "2" smd rect
			(at -1.301 0.004 90)
			(size 0.7 1.2)
			(layers "F.Cu" "F.Mask" "F.Paste")
			(net 9 "/Power/SW_1V2")
			(pinfunction "SW")
			(pintype "power_out")
		)
		(pad "3" smd rect
			(at -1.301 0.954 90)
			(size 0.7 1.2)
			(layers "F.Cu" "F.Mask" "F.Paste")
			(net 4 "+12V")
			(pinfunction "VIN")
			(pintype "power_in")
		)
		(pad "4" smd rect
			(at 1.299 0.954 90)
			(size 0.7 1.2)
			(layers "F.Cu" "F.Mask" "F.Paste")
			(net 71 "/Power/FB_1V2")
			(pinfunction "FB")
			(pintype "input")
		)
		(pad "5" smd rect
			(at 1.299 0.004 90)
			(size 0.7 1.2)
			(layers "F.Cu" "F.Mask" "F.Paste")
			(net 68 "/Power/EN_1V2")
			(pinfunction "EN")
			(pintype "input")
		)
		(pad "6" smd rect
			(at 1.299 -0.947 90)
			(size 0.7 1.2)
			(layers "F.Cu" "F.Mask" "F.Paste")
			(net 8 "Net-(U5-BST)")
			(pinfunction "BST")
			(pintype "output")
		)
	)
	(footprint "antmicro-footprints:TP_SMD_0.75mm"
		(layer "F.Cu")
		(at 158.496 97.89)
		(property "Reference" "TP1"
			(at -0.6096 -0.5588 180)
			(layer "F.SilkS")
			(hide yes)
			(effects
				(font
					(size 0.7 0.7)
					(thickness 0.15)
				)
				(justify left bottom)
			)
		)
		(property "Value" "TP_0.75mm_SMD"
			(at 0 1.2 0)
			(layer "F.Fab")
			(effects
				(font
					(size 0.7 0.7)
					(thickness 0.15)
				)
				(justify left bottom)
			)
		)
		(property "Description" "SMT test point"
			(at 0 0 0)
			(layer "F.Fab")
			(hide yes)
			(effects
				(font
					(size 1.27 1.27)
					(thickness 0.15)
				)
			)
		)
		(property "Author" "Antmicro"
			(at 0 0 0)
			(layer "F.Fab")
			(hide yes)
			(effects
				(font
					(size 1 1)
					(thickness 0.15)
				)
			)
		)
		(property "License" "Apache-2.0"
			(at 0 0 0)
			(layer "F.Fab")
			(hide yes)
			(effects
				(font
					(size 1 1)
					(thickness 0.15)
				)
			)
		)
		(property "MPN" ""
			(at 0 0 0)
			(layer "F.Fab")
			(hide yes)
			(effects
				(font
					(size 1 1)
					(thickness 0.15)
				)
			)
		)
		(property "Manufacturer" ""
			(at 0 0 0)
			(layer "F.Fab")
			(hide yes)
			(effects
				(font
					(size 1 1)
					(thickness 0.15)
				)
			)
		)
		(sheetname "/Connectors/")
		(sheetfile "connectors.kicad_sch")
		(fp_circle
			(center 0 0)
			(end 0.475 0)
			(stroke
				(width 0.05)
				(type default)
			)
			(fill no)
			(layer "F.CrtYd")
		)
		(pad "1" smd circle
			(at 0 0)
			(size 0.75 0.75)
			(layers "F.Cu" "F.Mask")
			(net 84 "/Connectors/MFP4")
			(pinfunction "1")
			(pintype "passive")
		)
	)
)
